# ZAIUS-LV_CARD-EVT1-X00-BOM-X01_20160825.xls — TBD AVL Qual (bom)
| NOTES: |  |  |  |  |  |  |
| The following items are alternates to the items listed in the Critical Components Qual tab. |  |  |  |  |  |  |
| These components will be included on near future, non-customer builds for validation and approval by both Dell and the ODM. |  |  |  |  |  |  |
| Item Description | ODM P/N | Dell PN | Vendor | Vendor PN | Build ?? | Estimated Completion Date |
| SATA connectors (black) |  |  |  |  |  |  |
| -  Alternate |  |  |  |  |  |  |
| SATA connectors (blue) |  |  |  |  |  |  |
| -  Alternate |  |  |  |  |  |  |
| PCIe retention |  |  |  |  |  |  |
| -  Alternate |  |  |  |  |  |  |
| RTC XTAL |  |  |  |  |  |  |
| -  Alternate |  |  |  |  |  |  |
| XTAL |  |  |  |  |  |  |
| -  Alternate |  |  |  |  |  |  |
